(kicad_pcb
	(version 20260206)
	(generator "pcbnew")
	(generator_version "10.0")
	(general
		(thickness 1.6)
		(legacy_teardrops no)
	)
	(paper "A4")
	(title_block
		(title "04192023_DAF0TMB3IC0_F0TG_MB_C_brd_V02_OCP.brd")
		(comment 1 "Grand Teton / footprint 3955 of 8354 (U25), pads 2103-2216 of 6102")
	)
	(layers
		(0 "F.Cu" signal "TOP")
		(4 "In1.Cu" signal "GND")
		(6 "In2.Cu" signal "IN1")
		(8 "In3.Cu" signal "GND1")
		(10 "In4.Cu" signal "IN2")
		(12 "In5.Cu" signal "GND2")
		(14 "In6.Cu" signal "IN3")
		(16 "In7.Cu" signal "GND3")
		(18 "In8.Cu" signal "VCC")
		(20 "In9.Cu" signal "VCC1")
		(22 "In10.Cu" signal "GND4")
		(24 "In11.Cu" signal "IN4")
		(26 "In12.Cu" signal "GND5")
		(28 "In13.Cu" signal "IN5")
		(30 "In14.Cu" signal "GND6")
		(32 "In15.Cu" signal "IN6")
		(34 "In16.Cu" signal "GND7")
		(2 "B.Cu" signal "BOTTOM")
		(9 "F.Adhes" user "F.Adhesive")
		(11 "B.Adhes" user "B.Adhesive")
		(13 "F.Paste" user "Package Geometry/Pastemask Top")
		(15 "B.Paste" user "Package Geometry/Pastemask Bottom")
		(5 "F.SilkS" user "Ref Des/Silkscreen Top")
		(7 "B.SilkS" user "Ref Des/Silkscreen Bottom")
		(1 "F.Mask" user "Board Geometry/Soldermask Top")
		(3 "B.Mask" user "Board Geometry/Soldermask Bottom")
		(17 "Dwgs.User" user "User.Drawings")
		(19 "Cmts.User" user "User.Comments")
		(21 "Eco1.User" user "User.Eco1")
		(23 "Eco2.User" user "User.Eco2")
		(25 "Edge.Cuts" user "Board Geometry/Outline")
		(27 "Margin" user)
		(31 "F.CrtYd" user "Package Geometry/Place Bound Top")
		(29 "B.CrtYd" user "Package Geometry/Place Bound Bottom")
		(35 "F.Fab" user "Ref Des/Assembly Top")
		(33 "B.Fab" user "Ref Des/Assembly Bottom")
	)
	(footprint ""
		(layer "F.Cu")
		(at 359.867962 -258.880102 180)
		(property "Reference" "U25"
			(at -45.78477 -62.086744 0)
			(unlocked yes)
			(layer "F.SilkS")
			(effects
				(font
					(size 0.7874 0.5842)
					(thickness 0.1524)
				)
			)
		)
		(property "Value" ""
			(at 0 0 180)
			(layer "F.Fab")
			(effects
				(font
					(size 1.27 1.27)
				)
			)
		)
		(duplicate_pad_numbers_are_jumpers no)
		(pad "BM16" smd circle
			(at -20.830032 6.839966 180)
			(size 0.450088 0.450088)
			(layers "F.Cu" "F.Mask" "F.Paste")
			(net "Net_1865")
		)
		(pad "BM17" smd circle
			(at -19.889978 6.839966 180)
			(size 0.450088 0.450088)
			(layers "F.Cu" "F.Mask" "F.Paste")
			(net "GND")
		)
		(pad "BM18" smd circle
			(at -18.949924 6.839966 180)
			(size 0.450088 0.450088)
			(layers "F.Cu" "F.Mask" "F.Paste")
			(net "M_J_CPU0_SB_CS_N<0>")
		)
		(pad "BM19" smd circle
			(at -18.010124 6.839966 180)
			(size 0.450088 0.450088)
			(layers "F.Cu" "F.Mask" "F.Paste")
			(net "PVDD11_S3_P0")
		)
		(pad "BM20" smd circle
			(at -17.07007 6.839966 180)
			(size 0.450088 0.450088)
			(layers "F.Cu" "F.Mask" "F.Paste")
			(net "Net_1857")
		)
		(pad "BM21" smd circle
			(at -16.130016 6.839966 180)
			(size 0.450088 0.450088)
			(layers "F.Cu" "F.Mask" "F.Paste")
			(net "M_I_CPU0_SB_CS_N<0>")
		)
		(pad "BM22" smd circle
			(at -15.189962 6.839966 180)
			(size 0.450088 0.450088)
			(layers "F.Cu" "F.Mask" "F.Paste")
			(net "PVDD11_S3_P0")
		)
		(pad "BM23" smd circle
			(at -14.249908 6.839966 180)
			(size 0.450088 0.450088)
			(layers "F.Cu" "F.Mask" "F.Paste")
			(net "GND")
		)
		(pad "BM24" smd circle
			(at -13.310108 6.839966 180)
			(size 0.450088 0.450088)
			(layers "F.Cu" "F.Mask" "F.Paste")
			(net "PVDD11_S3_P0")
		)
		(pad "BM25" smd circle
			(at -12.370054 6.839966 180)
			(size 0.450088 0.450088)
			(layers "F.Cu" "F.Mask" "F.Paste")
			(net "GND")
		)
		(pad "BM26" smd circle
			(at -11.43 6.839966 180)
			(size 0.450088 0.450088)
			(layers "F.Cu" "F.Mask" "F.Paste")
			(net "PVDD11_S3_P0")
		)
		(pad "BM27" smd circle
			(at -10.489946 6.839966 180)
			(size 0.450088 0.450088)
			(layers "F.Cu" "F.Mask" "F.Paste")
			(net "GND")
		)
		(pad "BM28" smd circle
			(at -9.549892 6.839966 180)
			(size 0.450088 0.450088)
			(layers "F.Cu" "F.Mask" "F.Paste")
			(net "PVDD11_S3_P0")
		)
		(pad "BM29" smd circle
			(at -8.610092 6.839966 180)
			(size 0.450088 0.450088)
			(layers "F.Cu" "F.Mask" "F.Paste")
			(net "GND")
		)
		(pad "BM30" smd circle
			(at -7.670038 6.839966 180)
			(size 0.450088 0.450088)
			(layers "F.Cu" "F.Mask" "F.Paste")
			(net "PVDD11_S3_P0")
		)
		(pad "BM31" smd circle
			(at -6.729984 6.839966 180)
			(size 0.450088 0.450088)
			(layers "F.Cu" "F.Mask" "F.Paste")
			(net "GND")
		)
		(pad "BM32" smd circle
			(at -5.78993 6.839966 180)
			(size 0.450088 0.450088)
			(layers "F.Cu" "F.Mask" "F.Paste")
			(net "PVDD11_S3_P0")
		)
		(pad "BM33" smd circle
			(at -4.849876 6.839966 180)
			(size 0.450088 0.450088)
			(layers "F.Cu" "F.Mask" "F.Paste")
			(net "GND")
		)
		(pad "BM34" smd circle
			(at -3.910076 6.839966 180)
			(size 0.450088 0.450088)
			(layers "F.Cu" "F.Mask" "F.Paste")
			(net "PVDD11_S3_P0")
		)
		(pad "BM35" smd circle
			(at -2.970022 6.839966 180)
			(size 0.450088 0.450088)
			(layers "F.Cu" "F.Mask" "F.Paste")
			(net "GND")
		)
		(pad "BM36" smd circle
			(at -2.029968 6.839966 180)
			(size 0.450088 0.450088)
			(layers "F.Cu" "F.Mask" "F.Paste")
			(net "PVDD11_S3_P0")
		)
		(pad "BM37" smd circle
			(at -1.089914 6.839966 180)
			(size 0.450088 0.450088)
			(layers "F.Cu" "F.Mask" "F.Paste")
			(net "GND")
		)
		(pad "BM39" smd circle
			(at 0.78994 6.839966 180)
			(size 0.450088 0.450088)
			(layers "F.Cu" "F.Mask" "F.Paste")
			(net "PVDD11_S3_P0")
		)
		(pad "BM40" smd circle
			(at 1.729994 6.839966 180)
			(size 0.450088 0.450088)
			(layers "F.Cu" "F.Mask" "F.Paste")
			(net "GND")
		)
		(pad "BM41" smd circle
			(at 2.670048 6.839966 180)
			(size 0.450088 0.450088)
			(layers "F.Cu" "F.Mask" "F.Paste")
			(net "PVDD11_S3_P0")
		)
		(pad "BM42" smd circle
			(at 3.610102 6.839966 180)
			(size 0.450088 0.450088)
			(layers "F.Cu" "F.Mask" "F.Paste")
			(net "GND")
		)
		(pad "BM43" smd circle
			(at 4.549902 6.839966 180)
			(size 0.450088 0.450088)
			(layers "F.Cu" "F.Mask" "F.Paste")
			(net "PVDD11_S3_P0")
		)
		(pad "BM44" smd circle
			(at 5.489956 6.839966 180)
			(size 0.450088 0.450088)
			(layers "F.Cu" "F.Mask" "F.Paste")
			(net "GND")
		)
		(pad "BM45" smd circle
			(at 6.43001 6.839966 180)
			(size 0.450088 0.450088)
			(layers "F.Cu" "F.Mask" "F.Paste")
			(net "PVDD11_S3_P0")
		)
		(pad "BM46" smd circle
			(at 7.370064 6.839966 180)
			(size 0.450088 0.450088)
			(layers "F.Cu" "F.Mask" "F.Paste")
			(net "GND")
		)
		(pad "BM47" smd circle
			(at 8.310118 6.839966 180)
			(size 0.450088 0.450088)
			(layers "F.Cu" "F.Mask" "F.Paste")
			(net "PVDD11_S3_P0")
		)
		(pad "BM48" smd circle
			(at 9.249918 6.839966 180)
			(size 0.450088 0.450088)
			(layers "F.Cu" "F.Mask" "F.Paste")
			(net "GND")
		)
		(pad "BM49" smd circle
			(at 10.189972 6.839966 180)
			(size 0.450088 0.450088)
			(layers "F.Cu" "F.Mask" "F.Paste")
			(net "PVDD11_S3_P0")
		)
		(pad "BM50" smd circle
			(at 11.130026 6.839966 180)
			(size 0.450088 0.450088)
			(layers "F.Cu" "F.Mask" "F.Paste")
			(net "GND")
		)
		(pad "BM51" smd circle
			(at 12.07008 6.839966 180)
			(size 0.450088 0.450088)
			(layers "F.Cu" "F.Mask" "F.Paste")
			(net "PVDDIO_P0")
		)
		(pad "BM52" smd circle
			(at 13.00988 6.839966 180)
			(size 0.450088 0.450088)
			(layers "F.Cu" "F.Mask" "F.Paste")
			(net "GND")
		)
		(pad "BM53" smd circle
			(at 13.949934 6.839966 180)
			(size 0.450088 0.450088)
			(layers "F.Cu" "F.Mask" "F.Paste")
			(net "PVDDIO_P0")
		)
		(pad "BM54" smd circle
			(at 14.889988 6.839966 180)
			(size 0.450088 0.450088)
			(layers "F.Cu" "F.Mask" "F.Paste")
			(net "GND")
		)
		(pad "BM55" smd circle
			(at 15.830042 6.839966 180)
			(size 0.450088 0.450088)
			(layers "F.Cu" "F.Mask" "F.Paste")
			(net "M_C_CPU0_SB_CS_N<0>")
		)
		(pad "BM56" smd circle
			(at 16.770096 6.839966 180)
			(size 0.450088 0.450088)
			(layers "F.Cu" "F.Mask" "F.Paste")
			(net "Net_1809")
		)
		(pad "BM57" smd circle
			(at 17.709896 6.839966 180)
			(size 0.450088 0.450088)
			(layers "F.Cu" "F.Mask" "F.Paste")
			(net "PVDDIO_P0")
		)
		(pad "BM58" smd circle
			(at 18.64995 6.839966 180)
			(size 0.450088 0.450088)
			(layers "F.Cu" "F.Mask" "F.Paste")
			(net "M_D_CPU0_SB_CS_N<0>")
		)
		(pad "BM59" smd circle
			(at 19.590004 6.839966 180)
			(size 0.450088 0.450088)
			(layers "F.Cu" "F.Mask" "F.Paste")
			(net "GND")
		)
		(pad "BM60" smd circle
			(at 20.530058 6.839966 180)
			(size 0.450088 0.450088)
			(layers "F.Cu" "F.Mask" "F.Paste")
			(net "Net_1817")
		)
		(pad "BM61" smd circle
			(at 21.470112 6.839966 180)
			(size 0.450088 0.450088)
			(layers "F.Cu" "F.Mask" "F.Paste")
			(net "GND")
		)
		(pad "BM62" smd circle
			(at 22.409912 6.839966 180)
			(size 0.450088 0.450088)
			(layers "F.Cu" "F.Mask" "F.Paste")
			(net "M_B_CPU0_SB_CS_N<0>")
		)
		(pad "BM63" smd circle
			(at 23.349966 6.839966 180)
			(size 0.450088 0.450088)
			(layers "F.Cu" "F.Mask" "F.Paste")
			(net "Net_1801")
		)
		(pad "BM64" smd circle
			(at 24.29002 6.839966 180)
			(size 0.450088 0.450088)
			(layers "F.Cu" "F.Mask" "F.Paste")
			(net "PVDDIO_P0")
		)
		(pad "BM65" smd circle
			(at 25.230074 6.839966 180)
			(size 0.450088 0.450088)
			(layers "F.Cu" "F.Mask" "F.Paste")
			(net "M_F_CPU0_SB_CS_N<0>")
		)
		(pad "BM66" smd circle
			(at 26.170128 6.839966 180)
			(size 0.450088 0.450088)
			(layers "F.Cu" "F.Mask" "F.Paste")
			(net "GND")
		)
		(pad "BM67" smd circle
			(at 27.109928 6.839966 180)
			(size 0.450088 0.450088)
			(layers "F.Cu" "F.Mask" "F.Paste")
			(net "Net_1833")
		)
		(pad "BM68" smd circle
			(at 28.049982 6.839966 180)
			(size 0.450088 0.450088)
			(layers "F.Cu" "F.Mask" "F.Paste")
			(net "GND")
		)
		(pad "BM69" smd circle
			(at 28.990036 6.839966 180)
			(size 0.450088 0.450088)
			(layers "F.Cu" "F.Mask" "F.Paste")
			(net "M_E_CPU0_SB_CS_N<0>")
		)
		(pad "BM70" smd circle
			(at 29.93009 6.839966 180)
			(size 0.450088 0.450088)
			(layers "F.Cu" "F.Mask" "F.Paste")
			(net "Net_1825")
		)
		(pad "BM71" smd circle
			(at 30.86989 6.839966 180)
			(size 0.450088 0.450088)
			(layers "F.Cu" "F.Mask" "F.Paste")
			(net "PVDDIO_P0")
		)
		(pad "BM72" smd circle
			(at 31.809944 6.839966 180)
			(size 0.450088 0.450088)
			(layers "F.Cu" "F.Mask" "F.Paste")
			(net "M_A_CPU0_SB_CS_N<0>")
		)
		(pad "BM73" smd circle
			(at 32.749998 6.839966 180)
			(size 0.450088 0.450088)
			(layers "F.Cu" "F.Mask" "F.Paste")
			(net "GND")
		)
		(pad "BM74" smd circle
			(at 33.690052 6.839966 180)
			(size 0.450088 0.450088)
			(layers "F.Cu" "F.Mask" "F.Paste")
			(net "Net_1793")
		)
		(pad "BN1" smd circle
			(at -34.459926 7.649972 180)
			(size 0.450088 0.450088)
			(layers "F.Cu" "F.Mask" "F.Paste")
			(net "GND")
		)
		(pad "BN2" smd circle
			(at -33.519872 7.649972 180)
			(size 0.450088 0.450088)
			(layers "F.Cu" "F.Mask" "F.Paste")
			(net "M_G_CPU0_SB_CS_N<1>")
		)
		(pad "BN3" smd circle
			(at -32.580072 7.649972 180)
			(size 0.450088 0.450088)
			(layers "F.Cu" "F.Mask" "F.Paste")
			(net "M_G_CPU0_SA_RSP<0>")
		)
		(pad "BN4" smd circle
			(at -31.640018 7.649972 180)
			(size 0.450088 0.450088)
			(layers "F.Cu" "F.Mask" "F.Paste")
			(net "GND")
		)
		(pad "BN5" smd circle
			(at -30.699964 7.649972 180)
			(size 0.450088 0.450088)
			(layers "F.Cu" "F.Mask" "F.Paste")
			(net "M_K_CPU0_SB_CS_N<1>")
		)
		(pad "BN6" smd circle
			(at -29.75991 7.649972 180)
			(size 0.450088 0.450088)
			(layers "F.Cu" "F.Mask" "F.Paste")
			(net "GND")
		)
		(pad "BN7" smd circle
			(at -28.82011 7.649972 180)
			(size 0.450088 0.450088)
			(layers "F.Cu" "F.Mask" "F.Paste")
			(net "M_K_CPU0_SA_RSP<0>")
		)
		(pad "BN8" smd circle
			(at -27.880056 7.649972 180)
			(size 0.450088 0.450088)
			(layers "F.Cu" "F.Mask" "F.Paste")
			(net "GND")
		)
		(pad "BN9" smd circle
			(at -26.940002 7.649972 180)
			(size 0.450088 0.450088)
			(layers "F.Cu" "F.Mask" "F.Paste")
			(net "M_L_CPU0_SB_CS_N<1>")
		)
		(pad "BN10" smd circle
			(at -25.999948 7.649972 180)
			(size 0.450088 0.450088)
			(layers "F.Cu" "F.Mask" "F.Paste")
			(net "M_L_CPU0_SA_RSP<0>")
		)
		(pad "BN11" smd circle
			(at -25.059894 7.649972 180)
			(size 0.450088 0.450088)
			(layers "F.Cu" "F.Mask" "F.Paste")
			(net "GND")
		)
		(pad "BN12" smd circle
			(at -24.120094 7.649972 180)
			(size 0.450088 0.450088)
			(layers "F.Cu" "F.Mask" "F.Paste")
			(net "M_H_CPU0_SB_CS_N<1>")
		)
		(pad "BN13" smd circle
			(at -23.18004 7.649972 180)
			(size 0.450088 0.450088)
			(layers "F.Cu" "F.Mask" "F.Paste")
			(net "GND")
		)
		(pad "BN14" smd circle
			(at -22.239986 7.649972 180)
			(size 0.450088 0.450088)
			(layers "F.Cu" "F.Mask" "F.Paste")
			(net "M_H_CPU0_SA_RSP<0>")
		)
		(pad "BN15" smd circle
			(at -21.299932 7.649972 180)
			(size 0.450088 0.450088)
			(layers "F.Cu" "F.Mask" "F.Paste")
			(net "GND")
		)
		(pad "BN16" smd circle
			(at -20.359878 7.649972 180)
			(size 0.450088 0.450088)
			(layers "F.Cu" "F.Mask" "F.Paste")
			(net "M_J_CPU0_SB_CS_N<1>")
		)
		(pad "BN17" smd circle
			(at -19.420078 7.649972 180)
			(size 0.450088 0.450088)
			(layers "F.Cu" "F.Mask" "F.Paste")
			(net "M_J_CPU0_SA_RSP<0>")
		)
		(pad "BN18" smd circle
			(at -18.480024 7.649972 180)
			(size 0.450088 0.450088)
			(layers "F.Cu" "F.Mask" "F.Paste")
			(net "GND")
		)
		(pad "BN19" smd circle
			(at -17.53997 7.649972 180)
			(size 0.450088 0.450088)
			(layers "F.Cu" "F.Mask" "F.Paste")
			(net "M_I_CPU0_SB_CS_N<1>")
		)
		(pad "BN20" smd circle
			(at -16.599916 7.649972 180)
			(size 0.450088 0.450088)
			(layers "F.Cu" "F.Mask" "F.Paste")
			(net "GND")
		)
		(pad "BN21" smd circle
			(at -15.660116 7.649972 180)
			(size 0.450088 0.450088)
			(layers "F.Cu" "F.Mask" "F.Paste")
			(net "M_I_CPU0_SA_RSP<0>")
		)
		(pad "BN22" smd circle
			(at -14.720062 7.649972 180)
			(size 0.450088 0.450088)
			(layers "F.Cu" "F.Mask" "F.Paste")
			(net "GND")
		)
		(pad "BN23" smd circle
			(at -13.780008 7.649972 180)
			(size 0.450088 0.450088)
			(layers "F.Cu" "F.Mask" "F.Paste")
			(net "P1V5_BAT")
		)
		(pad "BN24" smd circle
			(at -12.839954 7.649972 180)
			(size 0.450088 0.450088)
			(layers "F.Cu" "F.Mask" "F.Paste")
			(net "GND")
		)
		(pad "BN25" smd circle
			(at -11.8999 7.649972 180)
			(size 0.450088 0.450088)
			(layers "F.Cu" "F.Mask" "F.Paste")
			(net "PVDD11_S3_P0")
		)
		(pad "BN26" smd circle
			(at -10.9601 7.649972 180)
			(size 0.450088 0.450088)
			(layers "F.Cu" "F.Mask" "F.Paste")
			(net "GND")
		)
		(pad "BN27" smd circle
			(at -10.020046 7.649972 180)
			(size 0.450088 0.450088)
			(layers "F.Cu" "F.Mask" "F.Paste")
			(net "PVDDCR_CPU1_P0")
		)
		(pad "BN28" smd circle
			(at -9.079992 7.649972 180)
			(size 0.450088 0.450088)
			(layers "F.Cu" "F.Mask" "F.Paste")
			(net "GND")
		)
		(pad "BN29" smd circle
			(at -8.139938 7.649972 180)
			(size 0.450088 0.450088)
			(layers "F.Cu" "F.Mask" "F.Paste")
			(net "PVDD11_S3_P0")
		)
		(pad "BN30" smd circle
			(at -7.199884 7.649972 180)
			(size 0.450088 0.450088)
			(layers "F.Cu" "F.Mask" "F.Paste")
			(net "GND")
		)
		(pad "BN31" smd circle
			(at -6.260084 7.649972 180)
			(size 0.450088 0.450088)
			(layers "F.Cu" "F.Mask" "F.Paste")
			(net "PVDDCR_CPU1_P0")
		)
		(pad "BN32" smd circle
			(at -5.32003 7.649972 180)
			(size 0.450088 0.450088)
			(layers "F.Cu" "F.Mask" "F.Paste")
			(net "GND")
		)
		(pad "BN33" smd circle
			(at -4.379976 7.649972 180)
			(size 0.450088 0.450088)
			(layers "F.Cu" "F.Mask" "F.Paste")
			(net "PVDD11_S3_P0")
		)
		(pad "BN34" smd circle
			(at -3.439922 7.649972 180)
			(size 0.450088 0.450088)
			(layers "F.Cu" "F.Mask" "F.Paste")
			(net "GND")
		)
		(pad "BN35" smd circle
			(at -2.500122 7.649972 180)
			(size 0.450088 0.450088)
			(layers "F.Cu" "F.Mask" "F.Paste")
			(net "PVDDCR_CPU1_P0")
		)
		(pad "BN36" smd circle
			(at -1.560068 7.649972 180)
			(size 0.450088 0.450088)
			(layers "F.Cu" "F.Mask" "F.Paste")
			(net "GND")
		)
		(pad "BN40" smd circle
			(at 1.260094 7.649972 180)
			(size 0.450088 0.450088)
			(layers "F.Cu" "F.Mask" "F.Paste")
			(net "PVDD11_S3_P0")
		)
		(pad "BN41" smd circle
			(at 2.199894 7.649972 180)
			(size 0.450088 0.450088)
			(layers "F.Cu" "F.Mask" "F.Paste")
			(net "GND")
		)
		(pad "BN42" smd circle
			(at 3.139948 7.649972 180)
			(size 0.450088 0.450088)
			(layers "F.Cu" "F.Mask" "F.Paste")
			(net "PVDDCR_CPU1_P0")
		)
		(pad "BN43" smd circle
			(at 4.080002 7.649972 180)
			(size 0.450088 0.450088)
			(layers "F.Cu" "F.Mask" "F.Paste")
			(net "GND")
		)
		(pad "BN44" smd circle
			(at 5.020056 7.649972 180)
			(size 0.450088 0.450088)
			(layers "F.Cu" "F.Mask" "F.Paste")
			(net "PVDD11_S3_P0")
		)
		(pad "BN45" smd circle
			(at 5.96011 7.649972 180)
			(size 0.450088 0.450088)
			(layers "F.Cu" "F.Mask" "F.Paste")
			(net "GND")
		)
		(pad "BN46" smd circle
			(at 6.89991 7.649972 180)
			(size 0.450088 0.450088)
			(layers "F.Cu" "F.Mask" "F.Paste")
			(net "PVDDCR_CPU1_P0")
		)
		(pad "BN47" smd circle
			(at 7.839964 7.649972 180)
			(size 0.450088 0.450088)
			(layers "F.Cu" "F.Mask" "F.Paste")
			(net "GND")
		)
		(pad "BN48" smd circle
			(at 8.780018 7.649972 180)
			(size 0.450088 0.450088)
			(layers "F.Cu" "F.Mask" "F.Paste")
			(net "PVDD11_S3_P0")
		)
		(pad "BN49" smd circle
			(at 9.720072 7.649972 180)
			(size 0.450088 0.450088)
			(layers "F.Cu" "F.Mask" "F.Paste")
			(net "GND")
		)
		(pad "BN50" smd circle
			(at 10.659872 7.649972 180)
			(size 0.450088 0.450088)
			(layers "F.Cu" "F.Mask" "F.Paste")
			(net "PVDDCR_CPU1_P0")
		)
		(pad "BN51" smd circle
			(at 11.599926 7.649972 180)
			(size 0.450088 0.450088)
			(layers "F.Cu" "F.Mask" "F.Paste")
			(net "GND")
		)
		(pad "BN52" smd circle
			(at 12.53998 7.649972 180)
			(size 0.450088 0.450088)
			(layers "F.Cu" "F.Mask" "F.Paste")
			(net "PVDD_33_S5")
		)
		(pad "BN53" smd circle
			(at 13.480034 7.649972 180)
			(size 0.450088 0.450088)
			(layers "F.Cu" "F.Mask" "F.Paste")
			(net "GND")
		)
		(pad "BN54" smd circle
			(at 14.420088 7.649972 180)
			(size 0.450088 0.450088)
			(layers "F.Cu" "F.Mask" "F.Paste")
			(net "PVDDIO_P0")
		)
		(pad "BN55" smd circle
			(at 15.359888 7.649972 180)
			(size 0.450088 0.450088)
			(layers "F.Cu" "F.Mask" "F.Paste")
			(net "M_C_CPU0_SA_RSP<0>")
		)
		(pad "BN56" smd circle
			(at 16.299942 7.649972 180)
			(size 0.450088 0.450088)
			(layers "F.Cu" "F.Mask" "F.Paste")
			(net "GND")
		)
		(pad "BN57" smd circle
			(at 17.239996 7.649972 180)
			(size 0.450088 0.450088)
			(layers "F.Cu" "F.Mask" "F.Paste")
			(net "M_C_CPU0_SB_CS_N<1>")
		)
		(pad "BN58" smd circle
			(at 18.18005 7.649972 180)
			(size 0.450088 0.450088)
			(layers "F.Cu" "F.Mask" "F.Paste")
			(net "GND")
		)
		(pad "BN59" smd circle
			(at 19.120104 7.649972 180)
			(size 0.450088 0.450088)
			(layers "F.Cu" "F.Mask" "F.Paste")
			(net "M_D_CPU0_SA_RSP<0>")
		)
	)
)
